# BASEBOARD_FAB2 (Tioga Pass) — schematic netlist excerpt (pin names and nets, part order shuffled) for the footprints in the layout excerpt that follows; sources: Cadence DE-HDL packaged netlist, KiCad conversion of Wiwynn_Tioga_Pass_MB.brd

R7G22  RES  10.0K 1% CHIP  pkg 0402  page 189 : A = P3V3_STBY ; B = JTAG_TDO_R

(kicad_pcb
	(version 20260206)
	(generator "pcbnew")
	(generator_version "10.0")
	(general
		(thickness 1.6)
		(legacy_teardrops no)
	)
	(paper "A4")
	(title_block
		(title "Wiwynn_Tioga_Pass_MB.brd")
		(comment 1 "Tioga Pass / footprints 466-466 of 4770")
	)
	(layers
		(0 "F.Cu" signal "TOP")
		(4 "In1.Cu" signal "L2GND")
		(6 "In2.Cu" signal "L3")
		(8 "In3.Cu" signal "L4GND")
		(10 "In4.Cu" signal "L5")
		(12 "In5.Cu" signal "L6GND")
		(14 "In6.Cu" signal "L7VCC")
		(16 "In7.Cu" signal "L8VCC")
		(18 "In8.Cu" signal "L9GND")
		(20 "In9.Cu" signal "L10")
		(22 "In10.Cu" signal "L11GND")
		(24 "In11.Cu" signal "L12")
		(26 "In12.Cu" signal "L13GND")
		(2 "B.Cu" signal "BOTTOM")
		(9 "F.Adhes" user "F.Adhesive")
		(11 "B.Adhes" user "B.Adhesive")
		(13 "F.Paste" user "Package Geometry/Pastemask Top")
		(15 "B.Paste" user "Package Geometry/Pastemask Bottom")
		(5 "F.SilkS" user "Ref Des/Silkscreen Top")
		(7 "B.SilkS" user "Ref Des/Silkscreen Bottom")
		(1 "F.Mask" user "Board Geometry/Soldermask Top")
		(3 "B.Mask" user "Board Geometry/Soldermask Bottom")
		(17 "Dwgs.User" user "User.Drawings")
		(19 "Cmts.User" user "User.Comments")
		(21 "Eco1.User" user "User.Eco1")
		(23 "Eco2.User" user "User.Eco2")
		(25 "Edge.Cuts" user "Board Geometry/Outline")
		(27 "Margin" user)
		(31 "F.CrtYd" user "Package Geometry/Place Bound Top")
		(29 "B.CrtYd" user "Package Geometry/Place Bound Bottom")
		(35 "F.Fab" user "Ref Des/Assembly Top")
		(33 "B.Fab" user "Ref Des/Assembly Bottom")
	)
	(footprint ""
		(layer "F.Cu")
		(at 386.1054 1.651 -90)
		(property "Reference" "R7G22"
			(at 0 0 270)
			(layer "F.SilkS")
			(hide yes)
			(effects
				(font
					(size 1.27 1.27)
				)
			)
		)
		(property "Value" ""
			(at 0 0 270)
			(layer "F.Fab")
			(effects
				(font
					(size 1.27 1.27)
				)
			)
		)
		(duplicate_pad_numbers_are_jumpers no)
		(fp_poly
			(pts
				(xy -0.2794 -0.1016) (xy 0.2794 -0.1016) (xy 0.2794 0.9906) (xy -0.2794 0.9906)
			)
			(stroke
				(width 0)
				(type default)
			)
			(fill no)
			(layer "F.CrtYd")
		)
		(fp_line
			(start -0.2794 0.9906)
			(end 0.2794 0.9906)
			(stroke
				(width 0.1)
				(type default)
			)
			(layer "F.Fab")
		)
		(fp_line
			(start 0.2794 0.9906)
			(end 0.2794 -0.1016)
			(stroke
				(width 0.1)
				(type default)
			)
			(layer "F.Fab")
		)
		(fp_line
			(start -0.2794 -0.1016)
			(end -0.2794 0.9906)
			(stroke
				(width 0.1)
				(type default)
			)
			(layer "F.Fab")
		)
		(fp_line
			(start 0.2794 -0.1016)
			(end -0.2794 -0.1016)
			(stroke
				(width 0.1)
				(type default)
			)
			(layer "F.Fab")
		)
		(pad "1" smd rect
			(at 0 0 270)
			(size 0.508 0.508)
			(layers "F.Cu" "F.Mask" "F.Paste")
			(net "P3V3_STBY")
		)
		(pad "2" smd rect
			(at 0 0.889 270)
			(size 0.508 0.508)
			(layers "F.Cu" "F.Mask" "F.Paste")
			(net "JTAG_TDO_R")
		)
		(zone
			(layer "F.Cu")
			(hatch none 0.5)
			(connect_pads
				(clearance 0)
			)
			(min_thickness 0.25)
			(keepout
				(tracks not_allowed)
				(vias allowed)
				(pads allowed)
				(copperpour not_allowed)
				(footprints allowed)
			)
			(placement
				(enabled no)
				(sheetname "")
			)
			(fill
				(thermal_gap 0.5)
				(thermal_bridge_width 0.5)
				(island_removal_mode 0)
			)
			(polygon
				(pts
					(xy 385.4704 1.397) (xy 385.4704 1.905) (xy 385.8514 1.905) (xy 385.8514 1.397)
				)
			)
		)
		(zone
			(layer "F.Cu")
			(hatch none 0.5)
			(connect_pads
				(clearance 0)
			)
			(min_thickness 0.25)
			(keepout
				(tracks allowed)
				(vias not_allowed)
				(pads allowed)
				(copperpour not_allowed)
				(footprints allowed)
			)
			(placement
				(enabled no)
				(sheetname "")
			)
			(fill
				(thermal_gap 0.5)
				(thermal_bridge_width 0.5)
				(island_removal_mode 0)
			)
			(polygon
				(pts
					(xy 385.8514 1.397) (xy 385.8514 1.905) (xy 385.4704 1.905) (xy 385.4704 1.397)
				)
			)
		)
	)
)
